# T6G (Grand Teton) — schematic netlist excerpt (pin names and nets, part order shuffled) for the footprints in the layout excerpt that follows; sources: Cadence DE-HDL packaged netlist, KiCad conversion of 04192023_DAF0TMB3IC0_F0TG_MB_C_brd_V02_OCP.brd

R5032  Q_RES  4.7K 5% EMPTY  pkg 0402LF  page 55 : A = GND ; B = IRQ_CPU_BMC_NMI_N
PC2280  Q_CAP  10UF 16V 10% X6S  pkg C0805  page 146 : A = P12V_E1S_0 ; B = GND
C2605  Q_CAP  22UF 4V 20% X6S  pkg C0402  page 70 : A = PVDDIO_P0 ; B = GND

(kicad_pcb
	(version 20260206)
	(generator "pcbnew")
	(generator_version "10.0")
	(general
		(thickness 1.6)
		(legacy_teardrops no)
	)
	(paper "A4")
	(title_block
		(title "04192023_DAF0TMB3IC0_F0TG_MB_C_brd_V02_OCP.brd")
		(comment 1 "Grand Teton / footprints 6786-6788 of 8354")
	)
	(layers
		(0 "F.Cu" signal "TOP")
		(4 "In1.Cu" signal "GND")
		(6 "In2.Cu" signal "IN1")
		(8 "In3.Cu" signal "GND1")
		(10 "In4.Cu" signal "IN2")
		(12 "In5.Cu" signal "GND2")
		(14 "In6.Cu" signal "IN3")
		(16 "In7.Cu" signal "GND3")
		(18 "In8.Cu" signal "VCC")
		(20 "In9.Cu" signal "VCC1")
		(22 "In10.Cu" signal "GND4")
		(24 "In11.Cu" signal "IN4")
		(26 "In12.Cu" signal "GND5")
		(28 "In13.Cu" signal "IN5")
		(30 "In14.Cu" signal "GND6")
		(32 "In15.Cu" signal "IN6")
		(34 "In16.Cu" signal "GND7")
		(2 "B.Cu" signal "BOTTOM")
		(9 "F.Adhes" user "F.Adhesive")
		(11 "B.Adhes" user "B.Adhesive")
		(13 "F.Paste" user "Package Geometry/Pastemask Top")
		(15 "B.Paste" user "Package Geometry/Pastemask Bottom")
		(5 "F.SilkS" user "Ref Des/Silkscreen Top")
		(7 "B.SilkS" user "Ref Des/Silkscreen Bottom")
		(1 "F.Mask" user "Board Geometry/Soldermask Top")
		(3 "B.Mask" user "Board Geometry/Soldermask Bottom")
		(17 "Dwgs.User" user "User.Drawings")
		(19 "Cmts.User" user "User.Comments")
		(21 "Eco1.User" user "User.Eco1")
		(23 "Eco2.User" user "User.Eco2")
		(25 "Edge.Cuts" user "Board Geometry/Outline")
		(27 "Margin" user)
		(31 "F.CrtYd" user "Package Geometry/Place Bound Top")
		(29 "B.CrtYd" user "Package Geometry/Place Bound Bottom")
		(35 "F.Fab" user "Ref Des/Assembly Top")
		(33 "B.Fab" user "Ref Des/Assembly Bottom")
	)
	(footprint ""
		(layer "B.Cu")
		(at 94.488 -301.716948)
		(property "Reference" "R5032"
			(at 0 0 0)
			(layer "B.SilkS")
			(hide yes)
			(effects
				(font
					(size 1.27 1.27)
				)
				(justify mirror)
			)
		)
		(property "Value" ""
			(at 0 0 0)
			(layer "B.Fab")
			(effects
				(font
					(size 1.27 1.27)
				)
				(justify mirror)
			)
		)
		(duplicate_pad_numbers_are_jumpers no)
		(fp_line
			(start -0.7874 -0.4064)
			(end -0.7874 0.4064)
			(stroke
				(width 0.1524)
				(type default)
			)
			(layer "B.SilkS")
		)
		(fp_line
			(start -0.7874 0.4064)
			(end 0.7874 0.4064)
			(stroke
				(width 0.1524)
				(type default)
			)
			(layer "B.SilkS")
		)
		(fp_line
			(start 0.7874 -0.4064)
			(end -0.7874 -0.4064)
			(stroke
				(width 0.1524)
				(type default)
			)
			(layer "B.SilkS")
		)
		(fp_line
			(start 0.7874 0.4064)
			(end 0.7874 -0.4064)
			(stroke
				(width 0.1524)
				(type default)
			)
			(layer "B.SilkS")
		)
		(fp_line
			(start -0.67945 -0.3048)
			(end -0.67945 0.3048)
			(stroke
				(width 0.1)
				(type default)
			)
			(layer "B.Fab")
		)
		(fp_line
			(start -0.67945 0.3048)
			(end -0.120396 0.3048)
			(stroke
				(width 0.1)
				(type default)
			)
			(layer "B.Fab")
		)
		(fp_line
			(start -0.12065 -0.3048)
			(end -0.67945 -0.3048)
			(stroke
				(width 0.1)
				(type default)
			)
			(layer "B.Fab")
		)
		(fp_line
			(start -0.12065 -0.2794)
			(end -0.12065 -0.3048)
			(stroke
				(width 0.1)
				(type default)
			)
			(layer "B.Fab")
		)
		(fp_line
			(start -0.120396 0.2794)
			(end 0.12065 0.2794)
			(stroke
				(width 0.1)
				(type default)
			)
			(layer "B.Fab")
		)
		(fp_line
			(start -0.120396 0.3048)
			(end -0.120396 0.2794)
			(stroke
				(width 0.1)
				(type default)
			)
			(layer "B.Fab")
		)
		(fp_line
			(start 0.12065 -0.305054)
			(end 0.12065 -0.2794)
			(stroke
				(width 0.1)
				(type default)
			)
			(layer "B.Fab")
		)
		(fp_line
			(start 0.12065 -0.2794)
			(end -0.12065 -0.2794)
			(stroke
				(width 0.1)
				(type default)
			)
			(layer "B.Fab")
		)
		(fp_line
			(start 0.12065 0.2794)
			(end 0.12065 0.3048)
			(stroke
				(width 0.1)
				(type default)
			)
			(layer "B.Fab")
		)
		(fp_line
			(start 0.12065 0.3048)
			(end 0.67945 0.3048)
			(stroke
				(width 0.1)
				(type default)
			)
			(layer "B.Fab")
		)
		(fp_line
			(start 0.67945 -0.305054)
			(end 0.12065 -0.305054)
			(stroke
				(width 0.1)
				(type default)
			)
			(layer "B.Fab")
		)
		(fp_line
			(start 0.67945 0.3048)
			(end 0.67945 -0.305054)
			(stroke
				(width 0.1)
				(type default)
			)
			(layer "B.Fab")
		)
		(pad "1" smd circle
			(at 0.40005 0 180)
			(size 0 0)
			(layers "B.Cu" "B.Mask" "B.Paste")
			(net "GND")
		)
		(pad "2" smd circle
			(at -0.40005 0 180)
			(size 0 0)
			(layers "B.Cu" "B.Mask" "B.Paste")
			(net "IRQ_CPU_BMC_NMI_N")
		)
	)
	(footprint ""
		(layer "B.Cu")
		(at 246.01932 -53.923946 -90)
		(property "Reference" "PC2280"
			(at 0 0 90)
			(layer "B.SilkS")
			(hide yes)
			(effects
				(font
					(size 1.27 1.27)
				)
				(justify mirror)
			)
		)
		(property "Value" ""
			(at 0 0 90)
			(layer "B.Fab")
			(effects
				(font
					(size 1.27 1.27)
				)
				(justify mirror)
			)
		)
		(duplicate_pad_numbers_are_jumpers no)
		(fp_line
			(start -1.524 0.762)
			(end 1.524 0.762)
			(stroke
				(width 0.1524)
				(type default)
			)
			(layer "B.SilkS")
		)
		(fp_line
			(start 1.524 0.762)
			(end 1.524 -0.762)
			(stroke
				(width 0.1524)
				(type default)
			)
			(layer "B.SilkS")
		)
		(fp_line
			(start -1.524 -0.762)
			(end -1.524 0.762)
			(stroke
				(width 0.1524)
				(type default)
			)
			(layer "B.SilkS")
		)
		(fp_line
			(start 1.524 -0.762)
			(end -1.524 -0.762)
			(stroke
				(width 0.1524)
				(type default)
			)
			(layer "B.SilkS")
		)
		(fp_line
			(start -1.1049 0.724916)
			(end -1.1049 -0.724916)
			(stroke
				(width 0.1)
				(type default)
			)
			(layer "B.Fab")
		)
		(fp_line
			(start 1.1049 0.724916)
			(end -1.1049 0.724916)
			(stroke
				(width 0.1)
				(type default)
			)
			(layer "B.Fab")
		)
		(fp_line
			(start -1.1049 -0.724916)
			(end 1.1049 -0.724916)
			(stroke
				(width 0.1)
				(type default)
			)
			(layer "B.Fab")
		)
		(fp_line
			(start 1.1049 -0.724916)
			(end 1.1049 0.724916)
			(stroke
				(width 0.1)
				(type default)
			)
			(layer "B.Fab")
		)
		(pad "1" smd rect
			(at 0.889 0 270)
			(size 1.016 1.27)
			(layers "B.Cu" "B.Mask" "B.Paste")
			(net "P12V_E1S_0")
		)
		(pad "2" smd rect
			(at -0.889 0 270)
			(size 1.016 1.27)
			(layers "B.Cu" "B.Mask" "B.Paste")
			(net "GND")
		)
	)
	(footprint ""
		(layer "B.Cu")
		(at 346.373958 -261.870952)
		(property "Reference" "C2605"
			(at 0 0 0)
			(layer "B.SilkS")
			(hide yes)
			(effects
				(font
					(size 1.27 1.27)
				)
				(justify mirror)
			)
		)
		(property "Value" ""
			(at 0 0 0)
			(layer "B.Fab")
			(effects
				(font
					(size 1.27 1.27)
				)
				(justify mirror)
			)
		)
		(duplicate_pad_numbers_are_jumpers no)
		(fp_line
			(start -0.7874 -0.4064)
			(end -0.7874 0.4064)
			(stroke
				(width 0.1524)
				(type default)
			)
			(layer "B.SilkS")
		)
		(fp_line
			(start -0.7874 0.4064)
			(end 0.7874 0.4064)
			(stroke
				(width 0.1524)
				(type default)
			)
			(layer "B.SilkS")
		)
		(fp_line
			(start 0.7874 -0.4064)
			(end -0.7874 -0.4064)
			(stroke
				(width 0.1524)
				(type default)
			)
			(layer "B.SilkS")
		)
		(fp_line
			(start 0.7874 0.4064)
			(end 0.7874 -0.4064)
			(stroke
				(width 0.1524)
				(type default)
			)
			(layer "B.SilkS")
		)
		(fp_line
			(start -0.67945 -0.3048)
			(end -0.67945 0.3048)
			(stroke
				(width 0.1)
				(type default)
			)
			(layer "B.Fab")
		)
		(fp_line
			(start -0.67945 0.3048)
			(end -0.120396 0.3048)
			(stroke
				(width 0.1)
				(type default)
			)
			(layer "B.Fab")
		)
		(fp_line
			(start -0.12065 -0.3048)
			(end -0.67945 -0.3048)
			(stroke
				(width 0.1)
				(type default)
			)
			(layer "B.Fab")
		)
		(fp_line
			(start -0.12065 -0.2794)
			(end -0.12065 -0.3048)
			(stroke
				(width 0.1)
				(type default)
			)
			(layer "B.Fab")
		)
		(fp_line
			(start -0.120396 0.2794)
			(end 0.12065 0.2794)
			(stroke
				(width 0.1)
				(type default)
			)
			(layer "B.Fab")
		)
		(fp_line
			(start -0.120396 0.3048)
			(end -0.120396 0.2794)
			(stroke
				(width 0.1)
				(type default)
			)
			(layer "B.Fab")
		)
		(fp_line
			(start 0.12065 -0.305054)
			(end 0.12065 -0.2794)
			(stroke
				(width 0.1)
				(type default)
			)
			(layer "B.Fab")
		)
		(fp_line
			(start 0.12065 -0.2794)
			(end -0.12065 -0.2794)
			(stroke
				(width 0.1)
				(type default)
			)
			(layer "B.Fab")
		)
		(fp_line
			(start 0.12065 0.2794)
			(end 0.12065 0.3048)
			(stroke
				(width 0.1)
				(type default)
			)
			(layer "B.Fab")
		)
		(fp_line
			(start 0.12065 0.3048)
			(end 0.67945 0.3048)
			(stroke
				(width 0.1)
				(type default)
			)
			(layer "B.Fab")
		)
		(fp_line
			(start 0.67945 -0.305054)
			(end 0.12065 -0.305054)
			(stroke
				(width 0.1)
				(type default)
			)
			(layer "B.Fab")
		)
		(fp_line
			(start 0.67945 0.3048)
			(end 0.67945 -0.305054)
			(stroke
				(width 0.1)
				(type default)
			)
			(layer "B.Fab")
		)
		(pad "1" smd circle
			(at 0.40005 0 180)
			(size 0 0)
			(layers "B.Cu" "B.Mask" "B.Paste")
			(net "PVDDIO_P0")
		)
		(pad "2" smd circle
			(at -0.40005 0 180)
			(size 0 0)
			(layers "B.Cu" "B.Mask" "B.Paste")
			(net "GND")
		)
	)
)
